(kicad_pcb
	(version 20260206)
	(generator "pcbnew")
	(generator_version "10.0")
	(general
		(thickness 1.6)
		(legacy_teardrops no)
	)
	(paper "A4")
	(title_block
		(title "03242023_DA0F0TMBIJ0_F0T_Motherboard_J_brd_V01_OCP.brd")
		(comment 1 "Grand Teton / footprint 1585 of 6105 (U4), pads 114-227 of 749")
	)
	(layers
		(0 "F.Cu" signal "TOP")
		(4 "In1.Cu" signal "GND")
		(6 "In2.Cu" signal "IN1")
		(8 "In3.Cu" signal "GND1")
		(10 "In4.Cu" signal "IN2")
		(12 "In5.Cu" signal "GND2")
		(14 "In6.Cu" signal "IN3")
		(16 "In7.Cu" signal "GND3")
		(18 "In8.Cu" signal "VCC")
		(20 "In9.Cu" signal "VCC1")
		(22 "In10.Cu" signal "GND4")
		(24 "In11.Cu" signal "IN4")
		(26 "In12.Cu" signal "GND5")
		(28 "In13.Cu" signal "IN5")
		(30 "In14.Cu" signal "GND6")
		(32 "In15.Cu" signal "IN6")
		(34 "In16.Cu" signal "GND7")
		(2 "B.Cu" signal "BOTTOM")
		(9 "F.Adhes" user "F.Adhesive")
		(11 "B.Adhes" user "B.Adhesive")
		(13 "F.Paste" user "Package Geometry/Pastemask Top")
		(15 "B.Paste" user "Package Geometry/Pastemask Bottom")
		(5 "F.SilkS" user "Ref Des/Silkscreen Top")
		(7 "B.SilkS" user "Ref Des/Silkscreen Bottom")
		(1 "F.Mask" user "Board Geometry/Soldermask Top")
		(3 "B.Mask" user "Board Geometry/Soldermask Bottom")
		(17 "Dwgs.User" user "User.Drawings")
		(19 "Cmts.User" user "User.Comments")
		(21 "Eco1.User" user "User.Eco1")
		(23 "Eco2.User" user "User.Eco2")
		(25 "Edge.Cuts" user "Board Geometry/Outline")
		(27 "Margin" user)
		(31 "F.CrtYd" user "Package Geometry/Place Bound Top")
		(29 "B.CrtYd" user "Package Geometry/Place Bound Bottom")
		(35 "F.Fab" user "Ref Des/Assembly Top")
		(33 "B.Fab" user "Ref Des/Assembly Bottom")
	)
	(footprint ""
		(layer "F.Cu")
		(at 336.899758 -48.450246)
		(property "Reference" "U4"
			(at -13.479018 -11.486896 0)
			(unlocked yes)
			(layer "F.SilkS")
			(effects
				(font
					(size 0.7874 0.5842)
					(thickness 0.1524)
				)
				(justify left)
			)
		)
		(property "Value" ""
			(at 0 0 0)
			(layer "F.Fab")
			(effects
				(font
					(size 1.27 1.27)
				)
			)
		)
		(duplicate_pad_numbers_are_jumpers no)
		(pad "AF42" smd circle
			(at 9.899904 1.000506 180)
			(size 0.3048 0.3048)
			(layers "F.Cu" "F.Mask" "F.Paste")
			(net "GND")
		)
		(pad "AG1" smd oval
			(at -10.31494 1.500632 270)
			(size 0.254 0.3302)
			(layers "F.Cu" "F.Mask" "F.Paste")
			(net "FM_ESPI_FLASH_MODE")
		)
		(pad "AG3" smd circle
			(at -9.484868 1.500632 180)
			(size 0.3048 0.3048)
			(layers "F.Cu" "F.Mask" "F.Paste")
			(net "TP_PCH_GPP_D_20")
		)
		(pad "AG5" smd circle
			(at -8.654796 1.500632 180)
			(size 0.3048 0.3048)
			(layers "F.Cu" "F.Mask" "F.Paste")
			(net "GND")
		)
		(pad "AG7" smd circle
			(at -7.733792 1.4097 180)
			(size 0.381 0.381)
			(layers "F.Cu" "F.Mask" "F.Paste")
			(net "FM_ME_RCVR_N")
		)
		(pad "AG10" smd circle
			(at -6.105398 1.4097 180)
			(size 0.381 0.381)
			(layers "F.Cu" "F.Mask" "F.Paste")
			(net "FM_MFG_MODE")
		)
		(pad "AG13" smd circle
			(at -4.477512 1.4097 180)
			(size 0.381 0.381)
			(layers "F.Cu" "F.Mask" "F.Paste")
			(net "GND")
		)
		(pad "AG17" smd circle
			(at -2.4003 1.6002 180)
			(size 0.381 0.381)
			(layers "F.Cu" "F.Mask" "F.Paste")
			(net "P3V3_AUX")
		)
		(pad "AG19" smd circle
			(at -1.6002 1.6002 180)
			(size 0.381 0.381)
			(layers "F.Cu" "F.Mask" "F.Paste")
			(net "GND")
		)
		(pad "AG20" smd circle
			(at -0.8001 1.6002 180)
			(size 0.381 0.381)
			(layers "F.Cu" "F.Mask" "F.Paste")
			(net "P1V05_PCH_AUX")
		)
		(pad "AG22" smd circle
			(at 0 1.6002 180)
			(size 0.381 0.381)
			(layers "F.Cu" "F.Mask" "F.Paste")
			(net "P1V05_PCH_AUX")
		)
		(pad "AG24" smd circle
			(at 0.8001 1.6002 180)
			(size 0.381 0.381)
			(layers "F.Cu" "F.Mask" "F.Paste")
			(net "GND")
		)
		(pad "AG25" smd circle
			(at 1.6002 1.6002 180)
			(size 0.381 0.381)
			(layers "F.Cu" "F.Mask" "F.Paste")
			(net "P1V05_PCH_AUX")
		)
		(pad "AG27" smd circle
			(at 2.4003 1.6002 180)
			(size 0.381 0.381)
			(layers "F.Cu" "F.Mask" "F.Paste")
			(net "P1V05_PCH_AUX")
		)
		(pad "AG29" smd circle
			(at 3.663188 1.4097 180)
			(size 0.381 0.381)
			(layers "F.Cu" "F.Mask" "F.Paste")
			(net "P1V05_PCH_PLL_AUX")
		)
		(pad "AG32" smd circle
			(at 5.291582 1.4097 180)
			(size 0.381 0.381)
			(layers "F.Cu" "F.Mask" "F.Paste")
			(net "USB3_PCH_TX_DP<4>")
		)
		(pad "AG36" smd circle
			(at 6.919722 1.4097 180)
			(size 0.381 0.381)
			(layers "F.Cu" "F.Mask" "F.Paste")
			(net "P3E_PCH_E1S_TX_DP<3>")
		)
		(pad "AG39" smd circle
			(at 8.654796 1.500632 180)
			(size 0.3048 0.3048)
			(layers "F.Cu" "F.Mask" "F.Paste")
			(net "GND")
		)
		(pad "AG41" smd circle
			(at 9.484868 1.500632 180)
			(size 0.3048 0.3048)
			(layers "F.Cu" "F.Mask" "F.Paste")
			(net "TP_USB2_13_DP")
		)
		(pad "AG43" smd oval
			(at 10.31494 1.500632 270)
			(size 0.254 0.3302)
			(layers "F.Cu" "F.Mask" "F.Paste")
			(net "TP_USB2_13_DN")
		)
		(pad "AH2" smd circle
			(at -9.899904 2.001012 180)
			(size 0.3048 0.3048)
			(layers "F.Cu" "F.Mask" "F.Paste")
			(net "FM_PCHHOT_N")
		)
		(pad "AH4" smd circle
			(at -9.069832 2.001012 180)
			(size 0.3048 0.3048)
			(layers "F.Cu" "F.Mask" "F.Paste")
			(net "FM_ADR_TRIGGER_R_N")
		)
		(pad "AH8" smd circle
			(at -6.919722 1.8796 180)
			(size 0.381 0.381)
			(layers "F.Cu" "F.Mask" "F.Paste")
			(net "GND")
		)
		(pad "AH11" smd circle
			(at -5.291582 1.8796 180)
			(size 0.381 0.381)
			(layers "F.Cu" "F.Mask" "F.Paste")
			(net "IRQ_LVC3_WAKE_N")
		)
		(pad "AH15" smd circle
			(at -3.663188 1.8796 180)
			(size 0.381 0.381)
			(layers "F.Cu" "F.Mask" "F.Paste")
			(net "P3V3_RTC_AUX")
		)
		(pad "AH31" smd circle
			(at 4.477512 1.8796 180)
			(size 0.381 0.381)
			(layers "F.Cu" "F.Mask" "F.Paste")
			(net "GND")
		)
		(pad "AH34" smd circle
			(at 6.105398 1.8796 180)
			(size 0.381 0.381)
			(layers "F.Cu" "F.Mask" "F.Paste")
			(net "P3E_PCH_E1S_TX_DN<1>")
		)
		(pad "AH37" smd circle
			(at 7.733792 1.8796 180)
			(size 0.381 0.381)
			(layers "F.Cu" "F.Mask" "F.Paste")
			(net "P3E_PCH_E1S_TX_DP<2>")
		)
		(pad "AH40" smd circle
			(at 9.069832 2.001012 180)
			(size 0.3048 0.3048)
			(layers "F.Cu" "F.Mask" "F.Paste")
			(net "TP_USB2_11_DP")
		)
		(pad "AH42" smd circle
			(at 9.899904 2.001012 180)
			(size 0.3048 0.3048)
			(layers "F.Cu" "F.Mask" "F.Paste")
			(net "TP_USB2_11_DN")
		)
		(pad "AJ1" smd oval
			(at -10.31494 2.501138 270)
			(size 0.254 0.3302)
			(layers "F.Cu" "F.Mask" "F.Paste")
			(net "FM_FLASH_SECURITY_STRAP")
		)
		(pad "AJ3" smd circle
			(at -9.484868 2.501138 180)
			(size 0.3048 0.3048)
			(layers "F.Cu" "F.Mask" "F.Paste")
			(net "PU_LPC_PME_N")
		)
		(pad "AJ5" smd circle
			(at -8.654796 2.501138 180)
			(size 0.3048 0.3048)
			(layers "F.Cu" "F.Mask" "F.Paste")
			(net "GND")
		)
		(pad "AJ7" smd circle
			(at -7.733792 2.3495 180)
			(size 0.381 0.381)
			(layers "F.Cu" "F.Mask" "F.Paste")
			(net "TP_PCH_GPP_O_11")
		)
		(pad "AJ10" smd circle
			(at -6.105398 2.3495 180)
			(size 0.381 0.381)
			(layers "F.Cu" "F.Mask" "F.Paste")
			(net "RST_PCH_RSTBTN_R_N")
		)
		(pad "AJ13" smd circle
			(at -4.477512 2.3495 180)
			(size 0.381 0.381)
			(layers "F.Cu" "F.Mask" "F.Paste")
			(net "TP_PCH_SLP_S5_N")
		)
		(pad "AJ17" smd circle
			(at -2.4003 2.4003 180)
			(size 0.381 0.381)
			(layers "F.Cu" "F.Mask" "F.Paste")
			(net "P3V3_AUX")
		)
		(pad "AJ19" smd circle
			(at -1.6002 2.4003 180)
			(size 0.381 0.381)
			(layers "F.Cu" "F.Mask" "F.Paste")
			(net "GND")
		)
		(pad "AJ20" smd circle
			(at -0.8001 2.4003 180)
			(size 0.381 0.381)
			(layers "F.Cu" "F.Mask" "F.Paste")
			(net "P1V05_PCH_AUX")
		)
		(pad "AJ22" smd circle
			(at 0 2.4003 180)
			(size 0.381 0.381)
			(layers "F.Cu" "F.Mask" "F.Paste")
			(net "P1V05_PCH_AUX")
		)
		(pad "AJ24" smd circle
			(at 0.8001 2.4003 180)
			(size 0.381 0.381)
			(layers "F.Cu" "F.Mask" "F.Paste")
			(net "GND")
		)
		(pad "AJ25" smd circle
			(at 1.6002 2.4003 180)
			(size 0.381 0.381)
			(layers "F.Cu" "F.Mask" "F.Paste")
			(net "P1V05_PCH_AUX")
		)
		(pad "AJ27" smd circle
			(at 2.4003 2.4003 180)
			(size 0.381 0.381)
			(layers "F.Cu" "F.Mask" "F.Paste")
			(net "P1V05_PCH_AUX")
		)
		(pad "AJ29" smd circle
			(at 3.663188 2.3495 180)
			(size 0.381 0.381)
			(layers "F.Cu" "F.Mask" "F.Paste")
			(net "GND")
		)
		(pad "AJ32" smd circle
			(at 5.291582 2.3495 180)
			(size 0.381 0.381)
			(layers "F.Cu" "F.Mask" "F.Paste")
			(net "P3E_PCH_E1S_TX_DP<1>")
		)
		(pad "AJ36" smd circle
			(at 6.919722 2.3495 180)
			(size 0.381 0.381)
			(layers "F.Cu" "F.Mask" "F.Paste")
			(net "GND")
		)
		(pad "AJ39" smd circle
			(at 8.654796 2.501138 180)
			(size 0.3048 0.3048)
			(layers "F.Cu" "F.Mask" "F.Paste")
			(net "GND")
		)
		(pad "AJ41" smd circle
			(at 9.484868 2.501138 180)
			(size 0.3048 0.3048)
			(layers "F.Cu" "F.Mask" "F.Paste")
			(net "TP_USB2_9_DP")
		)
		(pad "AJ43" smd oval
			(at 10.31494 2.501138 270)
			(size 0.254 0.3302)
			(layers "F.Cu" "F.Mask" "F.Paste")
			(net "TP_USB2_9_DN")
		)
		(pad "AK2" smd circle
			(at -9.899904 3.001518 180)
			(size 0.3048 0.3048)
			(layers "F.Cu" "F.Mask" "F.Paste")
			(net "GND")
		)
		(pad "AK4" smd circle
			(at -9.069832 3.001518 180)
			(size 0.3048 0.3048)
			(layers "F.Cu" "F.Mask" "F.Paste")
			(net "GND")
		)
		(pad "AK8" smd circle
			(at -6.919722 2.8194 180)
			(size 0.381 0.381)
			(layers "F.Cu" "F.Mask" "F.Paste")
			(net "TP_SLP_LAN_N")
		)
		(pad "AK11" smd circle
			(at -5.291582 2.8194 180)
			(size 0.381 0.381)
			(layers "F.Cu" "F.Mask" "F.Paste")
			(net "GND")
		)
		(pad "AK15" smd circle
			(at -3.663188 2.8194 180)
			(size 0.381 0.381)
			(layers "F.Cu" "F.Mask" "F.Paste")
			(net "P3V3_AUX")
		)
		(pad "AK31" smd circle
			(at 4.477512 2.8194 180)
			(size 0.381 0.381)
			(layers "F.Cu" "F.Mask" "F.Paste")
			(net "P3E_PCH_M2_TX_DP<0>")
		)
		(pad "AK34" smd circle
			(at 6.105398 2.8194 180)
			(size 0.381 0.381)
			(layers "F.Cu" "F.Mask" "F.Paste")
			(net "P3E_PCH_M2_TX_DN<3>")
		)
		(pad "AK37" smd circle
			(at 7.733792 2.8194 180)
			(size 0.381 0.381)
			(layers "F.Cu" "F.Mask" "F.Paste")
			(net "GND")
		)
		(pad "AK40" smd circle
			(at 9.069832 3.001518 180)
			(size 0.3048 0.3048)
			(layers "F.Cu" "F.Mask" "F.Paste")
			(net "USB2_7_DP")
		)
		(pad "AK42" smd circle
			(at 9.899904 3.001518 180)
			(size 0.3048 0.3048)
			(layers "F.Cu" "F.Mask" "F.Paste")
			(net "USB2_7_DN")
		)
		(pad "AL1" smd oval
			(at -10.31494 3.501644 270)
			(size 0.254 0.3302)
			(layers "F.Cu" "F.Mask" "F.Paste")
			(net "PU_SMB_PCH_PLD_3V3AUX_SCL")
		)
		(pad "AL3" smd circle
			(at -9.484868 3.501644 180)
			(size 0.3048 0.3048)
			(layers "F.Cu" "F.Mask" "F.Paste")
			(net "FM_BIOS_POST_CMPLT_N")
		)
		(pad "AL5" smd circle
			(at -8.654796 3.501644 180)
			(size 0.3048 0.3048)
			(layers "F.Cu" "F.Mask" "F.Paste")
			(net "FM_ADR_MODE1")
		)
		(pad "AL7" smd circle
			(at -7.733792 3.2893 180)
			(size 0.381 0.381)
			(layers "F.Cu" "F.Mask" "F.Paste")
			(net "FM_PCH_SLP_SUS_N")
		)
		(pad "AL10" smd circle
			(at -6.105398 3.2893 180)
			(size 0.381 0.381)
			(layers "F.Cu" "F.Mask" "F.Paste")
			(net "PWRGD_SYS_PWROK")
		)
		(pad "AL13" smd circle
			(at -4.477512 3.2893 180)
			(size 0.381 0.381)
			(layers "F.Cu" "F.Mask" "F.Paste")
			(net "FM_PCH_SLP_S4_N")
		)
		(pad "AL17" smd circle
			(at -2.4003 3.2004 180)
			(size 0.381 0.381)
			(layers "F.Cu" "F.Mask" "F.Paste")
			(net "P3V3_AUX")
		)
		(pad "AL19" smd circle
			(at -1.6002 3.2004 180)
			(size 0.381 0.381)
			(layers "F.Cu" "F.Mask" "F.Paste")
			(net "GND")
		)
		(pad "AL20" smd circle
			(at -0.8001 3.2004 180)
			(size 0.381 0.381)
			(layers "F.Cu" "F.Mask" "F.Paste")
			(net "P1V05_PCH_AUX")
		)
		(pad "AL22" smd circle
			(at 0 3.2004 180)
			(size 0.381 0.381)
			(layers "F.Cu" "F.Mask" "F.Paste")
			(net "P1V05_PCH_AUX")
		)
		(pad "AL24" smd circle
			(at 0.8001 3.2004 180)
			(size 0.381 0.381)
			(layers "F.Cu" "F.Mask" "F.Paste")
			(net "GND")
		)
		(pad "AL25" smd circle
			(at 1.6002 3.2004 180)
			(size 0.381 0.381)
			(layers "F.Cu" "F.Mask" "F.Paste")
			(net "P1V05_PCH_PLL_AUX")
		)
		(pad "AL27" smd circle
			(at 2.4003 3.2004 180)
			(size 0.381 0.381)
			(layers "F.Cu" "F.Mask" "F.Paste")
			(net "GND")
		)
		(pad "AL29" smd circle
			(at 3.663188 3.2893 180)
			(size 0.381 0.381)
			(layers "F.Cu" "F.Mask" "F.Paste")
			(net "GND")
		)
		(pad "AL32" smd circle
			(at 5.291582 3.2893 180)
			(size 0.381 0.381)
			(layers "F.Cu" "F.Mask" "F.Paste")
			(net "P3E_PCH_M2_TX_DN<0>")
		)
		(pad "AL36" smd circle
			(at 6.919722 3.2893 180)
			(size 0.381 0.381)
			(layers "F.Cu" "F.Mask" "F.Paste")
			(net "P3E_PCH_E1S_TX_DN<0>")
		)
		(pad "AL39" smd circle
			(at 8.654796 3.501644 180)
			(size 0.3048 0.3048)
			(layers "F.Cu" "F.Mask" "F.Paste")
			(net "GND")
		)
		(pad "AL41" smd circle
			(at 9.484868 3.501644 180)
			(size 0.3048 0.3048)
			(layers "F.Cu" "F.Mask" "F.Paste")
			(net "USB2_5_DP")
		)
		(pad "AL43" smd oval
			(at 10.31494 3.501644 270)
			(size 0.254 0.3302)
			(layers "F.Cu" "F.Mask" "F.Paste")
			(net "USB2_5_DN")
		)
		(pad "AM8" smd circle
			(at -6.919722 3.7592 180)
			(size 0.381 0.381)
			(layers "F.Cu" "F.Mask" "F.Paste")
			(net "GND")
		)
		(pad "AM11" smd circle
			(at -5.291582 3.7592 180)
			(size 0.381 0.381)
			(layers "F.Cu" "F.Mask" "F.Paste")
			(net "TP_PCH_SLP_A_N")
		)
		(pad "AM15" smd circle
			(at -3.663188 3.7592 180)
			(size 0.381 0.381)
			(layers "F.Cu" "F.Mask" "F.Paste")
			(net "GND")
		)
		(pad "AM31" smd circle
			(at 4.477512 3.7592 180)
			(size 0.381 0.381)
			(layers "F.Cu" "F.Mask" "F.Paste")
			(net "GND")
		)
		(pad "AM34" smd circle
			(at 6.105398 3.7592 180)
			(size 0.381 0.381)
			(layers "F.Cu" "F.Mask" "F.Paste")
			(net "P3E_PCH_M2_TX_DP<3>")
		)
		(pad "AM37" smd circle
			(at 7.733792 3.7592 180)
			(size 0.381 0.381)
			(layers "F.Cu" "F.Mask" "F.Paste")
			(net "P3E_PCH_E1S_TX_DP<0>")
		)
		(pad "AN2" smd circle
			(at -9.899904 4.002024 180)
			(size 0.3048 0.3048)
			(layers "F.Cu" "F.Mask" "F.Paste")
			(net "PU_PCH_PLD_3V3AUX_ALERT_N")
		)
		(pad "AN4" smd circle
			(at -9.069832 4.002024 180)
			(size 0.3048 0.3048)
			(layers "F.Cu" "F.Mask" "F.Paste")
			(net "PU_SMB_SML3_3V3AUX_PCH_SCL")
		)
		(pad "AN7" smd circle
			(at -7.733792 4.2291 180)
			(size 0.381 0.381)
			(layers "F.Cu" "F.Mask" "F.Paste")
			(net "PU_ACPRESENT")
		)
		(pad "AN10" smd circle
			(at -6.105398 4.2291 180)
			(size 0.381 0.381)
			(layers "F.Cu" "F.Mask" "F.Paste")
			(net "FM_PCH_SPARE0")
		)
		(pad "AN13" smd circle
			(at -4.477512 4.2291 180)
			(size 0.381 0.381)
			(layers "F.Cu" "F.Mask" "F.Paste")
			(net "GND")
		)
		(pad "AN16" smd circle
			(at -2.849118 4.2291 180)
			(size 0.381 0.381)
			(layers "F.Cu" "F.Mask" "F.Paste")
			(net "GND")
		)
		(pad "AN20" smd circle
			(at -1.220978 4.2291 180)
			(size 0.381 0.381)
			(layers "F.Cu" "F.Mask" "F.Paste")
			(net "P3V3_AUX")
		)
		(pad "AN23" smd circle
			(at 0.406908 4.2291 180)
			(size 0.381 0.381)
			(layers "F.Cu" "F.Mask" "F.Paste")
			(net "P1V05_PCH_AUX")
		)
		(pad "AN26" smd circle
			(at 2.035302 4.2291 180)
			(size 0.381 0.381)
			(layers "F.Cu" "F.Mask" "F.Paste")
			(net "TP_PCH_RSVD<15>")
		)
		(pad "AN29" smd circle
			(at 3.663188 4.2291 180)
			(size 0.381 0.381)
			(layers "F.Cu" "F.Mask" "F.Paste")
			(net "GND")
		)
		(pad "AN32" smd circle
			(at 5.291582 4.2291 180)
			(size 0.381 0.381)
			(layers "F.Cu" "F.Mask" "F.Paste")
			(net "GND")
		)
		(pad "AN36" smd circle
			(at 6.919722 4.2291 180)
			(size 0.381 0.381)
			(layers "F.Cu" "F.Mask" "F.Paste")
			(net "P3E_PCH_M2_TX_DN<1>")
		)
		(pad "AN40" smd circle
			(at 9.069832 4.002024 180)
			(size 0.3048 0.3048)
			(layers "F.Cu" "F.Mask" "F.Paste")
			(net "USB2_3_DP")
		)
		(pad "AN42" smd circle
			(at 9.899904 4.002024 180)
			(size 0.3048 0.3048)
			(layers "F.Cu" "F.Mask" "F.Paste")
			(net "USB2_3_DN")
		)
		(pad "AP1" smd oval
			(at -10.31494 4.50215 270)
			(size 0.254 0.3302)
			(layers "F.Cu" "F.Mask" "F.Paste")
			(net "SMB_SML1_PMBUS_3V3AUX_PCH_SCL_1")
		)
		(pad "AP3" smd circle
			(at -9.484868 4.50215 180)
			(size 0.3048 0.3048)
			(layers "F.Cu" "F.Mask" "F.Paste")
			(net "PD_PCH_GPPC_C10")
		)
		(pad "AP5" smd circle
			(at -8.654796 4.50215 180)
			(size 0.3048 0.3048)
			(layers "F.Cu" "F.Mask" "F.Paste")
			(net "GND")
		)
		(pad "AP8" smd circle
			(at -6.919722 4.699 180)
			(size 0.381 0.381)
			(layers "F.Cu" "F.Mask" "F.Paste")
			(net "FM_PCH_SLP_S3_N")
		)
		(pad "AP11" smd circle
			(at -5.291582 4.699 180)
			(size 0.381 0.381)
			(layers "F.Cu" "F.Mask" "F.Paste")
			(net "GND")
		)
		(pad "AP15" smd circle
			(at -3.663188 4.699 180)
			(size 0.381 0.381)
			(layers "F.Cu" "F.Mask" "F.Paste")
			(net "IRQ_PCH_CPU_NMI_EVENT_R_N")
		)
		(pad "AP18" smd circle
			(at -2.035302 4.699 180)
			(size 0.381 0.381)
			(layers "F.Cu" "F.Mask" "F.Paste")
			(net "GND")
		)
		(pad "AP21" smd circle
			(at -0.406908 4.699 180)
			(size 0.381 0.381)
			(layers "F.Cu" "F.Mask" "F.Paste")
			(net "P1V05_PCH_AUX")
		)
		(pad "AP24" smd circle
			(at 1.220978 4.699 180)
			(size 0.381 0.381)
			(layers "F.Cu" "F.Mask" "F.Paste")
			(net "GND")
		)
		(pad "AP28" smd circle
			(at 2.849118 4.699 180)
			(size 0.381 0.381)
			(layers "F.Cu" "F.Mask" "F.Paste")
			(net "GND")
		)
		(pad "AP31" smd circle
			(at 4.477512 4.699 180)
			(size 0.381 0.381)
			(layers "F.Cu" "F.Mask" "F.Paste")
			(net "PCH_PCIEUP_RCOMPN")
		)
		(pad "AP34" smd circle
			(at 6.105398 4.699 180)
			(size 0.381 0.381)
			(layers "F.Cu" "F.Mask" "F.Paste")
			(net "P3E_PCH_M2_TX_DP<1>")
		)
		(pad "AP37" smd circle
			(at 7.733792 4.699 180)
			(size 0.381 0.381)
			(layers "F.Cu" "F.Mask" "F.Paste")
			(net "GND")
		)
		(pad "AP39" smd circle
			(at 8.654796 4.50215 180)
			(size 0.3048 0.3048)
			(layers "F.Cu" "F.Mask" "F.Paste")
			(net "GND")
		)
		(pad "AP41" smd circle
			(at 9.484868 4.50215 180)
			(size 0.3048 0.3048)
			(layers "F.Cu" "F.Mask" "F.Paste")
			(net "TP_USB2_1_DP")
		)
		(pad "AP43" smd oval
			(at 10.31494 4.50215 270)
			(size 0.254 0.3302)
			(layers "F.Cu" "F.Mask" "F.Paste")
			(net "TP_USB2_1_DN")
		)
	)
)
